# T6G (Grand Teton) — schematic netlist excerpt (pin names and nets, part order shuffled) for the footprints in the layout excerpt that follows; sources: Cadence DE-HDL packaged netlist, KiCad conversion of 04192023_DAF0TMB3IC0_F0TG_MB_C_brd_V02_OCP.brd

PR3812  Q_RES  15K 1% CHIP  pkg 0402LF  page 140 : A = P3V3_OCP_OV_2 ; B = GND
C505  Q_CAP  22UF 4V 20% X6S  pkg C0402  page 279 : A = P1V8_CPU0_RT0_1A ; B = GND

(kicad_pcb
	(version 20260206)
	(generator "pcbnew")
	(generator_version "10.0")
	(general
		(thickness 1.6)
		(legacy_teardrops no)
	)
	(paper "A4")
	(title_block
		(title "04192023_DAF0TMB3IC0_F0TG_MB_C_brd_V02_OCP.brd")
		(comment 1 "Grand Teton / footprints 2980-2981 of 8354")
	)
	(layers
		(0 "F.Cu" signal "TOP")
		(4 "In1.Cu" signal "GND")
		(6 "In2.Cu" signal "IN1")
		(8 "In3.Cu" signal "GND1")
		(10 "In4.Cu" signal "IN2")
		(12 "In5.Cu" signal "GND2")
		(14 "In6.Cu" signal "IN3")
		(16 "In7.Cu" signal "GND3")
		(18 "In8.Cu" signal "VCC")
		(20 "In9.Cu" signal "VCC1")
		(22 "In10.Cu" signal "GND4")
		(24 "In11.Cu" signal "IN4")
		(26 "In12.Cu" signal "GND5")
		(28 "In13.Cu" signal "IN5")
		(30 "In14.Cu" signal "GND6")
		(32 "In15.Cu" signal "IN6")
		(34 "In16.Cu" signal "GND7")
		(2 "B.Cu" signal "BOTTOM")
		(9 "F.Adhes" user "F.Adhesive")
		(11 "B.Adhes" user "B.Adhesive")
		(13 "F.Paste" user "Package Geometry/Pastemask Top")
		(15 "B.Paste" user "Package Geometry/Pastemask Bottom")
		(5 "F.SilkS" user "Ref Des/Silkscreen Top")
		(7 "B.SilkS" user "Ref Des/Silkscreen Bottom")
		(1 "F.Mask" user "Board Geometry/Soldermask Top")
		(3 "B.Mask" user "Board Geometry/Soldermask Bottom")
		(17 "Dwgs.User" user "User.Drawings")
		(19 "Cmts.User" user "User.Comments")
		(21 "Eco1.User" user "User.Eco1")
		(23 "Eco2.User" user "User.Eco2")
		(25 "Edge.Cuts" user "Board Geometry/Outline")
		(27 "Margin" user)
		(31 "F.CrtYd" user "Package Geometry/Place Bound Top")
		(29 "B.CrtYd" user "Package Geometry/Place Bound Bottom")
		(35 "F.Fab" user "Ref Des/Assembly Top")
		(33 "B.Fab" user "Ref Des/Assembly Bottom")
	)
	(footprint ""
		(layer "F.Cu")
		(at 325.49338 -394.82268 90)
		(property "Reference" "C505"
			(at 0 0 90)
			(layer "F.SilkS")
			(hide yes)
			(effects
				(font
					(size 1.27 1.27)
				)
			)
		)
		(property "Value" ""
			(at 0 0 90)
			(layer "F.Fab")
			(effects
				(font
					(size 1.27 1.27)
				)
			)
		)
		(duplicate_pad_numbers_are_jumpers no)
		(fp_line
			(start 0.7874 -0.4064)
			(end 0.7874 0.4064)
			(stroke
				(width 0.1524)
				(type default)
			)
			(layer "F.SilkS")
		)
		(fp_line
			(start -0.7874 -0.4064)
			(end 0.7874 -0.4064)
			(stroke
				(width 0.1524)
				(type default)
			)
			(layer "F.SilkS")
		)
		(fp_line
			(start 0.7874 0.4064)
			(end -0.7874 0.4064)
			(stroke
				(width 0.1524)
				(type default)
			)
			(layer "F.SilkS")
		)
		(fp_line
			(start -0.7874 0.4064)
			(end -0.7874 -0.4064)
			(stroke
				(width 0.1524)
				(type default)
			)
			(layer "F.SilkS")
		)
		(fp_line
			(start -0.12065 -0.305054)
			(end -0.12065 -0.2794)
			(stroke
				(width 0.1)
				(type default)
			)
			(layer "F.Fab")
		)
		(fp_line
			(start -0.67945 -0.305054)
			(end -0.12065 -0.305054)
			(stroke
				(width 0.1)
				(type default)
			)
			(layer "F.Fab")
		)
		(fp_line
			(start 0.67945 -0.3048)
			(end 0.67945 0.3048)
			(stroke
				(width 0.1)
				(type default)
			)
			(layer "F.Fab")
		)
		(fp_line
			(start 0.12065 -0.3048)
			(end 0.67945 -0.3048)
			(stroke
				(width 0.1)
				(type default)
			)
			(layer "F.Fab")
		)
		(fp_line
			(start 0.12065 -0.2794)
			(end 0.12065 -0.3048)
			(stroke
				(width 0.1)
				(type default)
			)
			(layer "F.Fab")
		)
		(fp_line
			(start -0.12065 -0.2794)
			(end 0.12065 -0.2794)
			(stroke
				(width 0.1)
				(type default)
			)
			(layer "F.Fab")
		)
		(fp_line
			(start 0.120396 0.2794)
			(end -0.12065 0.2794)
			(stroke
				(width 0.1)
				(type default)
			)
			(layer "F.Fab")
		)
		(fp_line
			(start -0.12065 0.2794)
			(end -0.12065 0.3048)
			(stroke
				(width 0.1)
				(type default)
			)
			(layer "F.Fab")
		)
		(fp_line
			(start 0.67945 0.3048)
			(end 0.120396 0.3048)
			(stroke
				(width 0.1)
				(type default)
			)
			(layer "F.Fab")
		)
		(fp_line
			(start 0.120396 0.3048)
			(end 0.120396 0.2794)
			(stroke
				(width 0.1)
				(type default)
			)
			(layer "F.Fab")
		)
		(fp_line
			(start -0.12065 0.3048)
			(end -0.67945 0.3048)
			(stroke
				(width 0.1)
				(type default)
			)
			(layer "F.Fab")
		)
		(fp_line
			(start -0.67945 0.3048)
			(end -0.67945 -0.305054)
			(stroke
				(width 0.1)
				(type default)
			)
			(layer "F.Fab")
		)
		(pad "1" smd circle
			(at -0.40005 0 90)
			(size 0 0)
			(layers "F.Cu" "F.Mask" "F.Paste")
			(net "P1V8_CPU0_RT0_1A")
		)
		(pad "2" smd circle
			(at 0.40005 0 90)
			(size 0 0)
			(layers "F.Cu" "F.Mask" "F.Paste")
			(net "GND")
		)
	)
	(footprint ""
		(layer "F.Cu")
		(at 95.39097 -61.87821)
		(property "Reference" "PR3812"
			(at 0 0 0)
			(layer "F.SilkS")
			(hide yes)
			(effects
				(font
					(size 1.27 1.27)
				)
			)
		)
		(property "Value" ""
			(at 0 0 0)
			(layer "F.Fab")
			(effects
				(font
					(size 1.27 1.27)
				)
			)
		)
		(duplicate_pad_numbers_are_jumpers no)
		(fp_line
			(start -0.7874 -0.4064)
			(end 0.7874 -0.4064)
			(stroke
				(width 0.1524)
				(type default)
			)
			(layer "F.SilkS")
		)
		(fp_line
			(start -0.7874 0.4064)
			(end -0.7874 -0.4064)
			(stroke
				(width 0.1524)
				(type default)
			)
			(layer "F.SilkS")
		)
		(fp_line
			(start 0.7874 -0.4064)
			(end 0.7874 0.4064)
			(stroke
				(width 0.1524)
				(type default)
			)
			(layer "F.SilkS")
		)
		(fp_line
			(start 0.7874 0.4064)
			(end -0.7874 0.4064)
			(stroke
				(width 0.1524)
				(type default)
			)
			(layer "F.SilkS")
		)
		(fp_line
			(start -0.67945 -0.305054)
			(end -0.12065 -0.305054)
			(stroke
				(width 0.1)
				(type default)
			)
			(layer "F.Fab")
		)
		(fp_line
			(start -0.67945 0.3048)
			(end -0.67945 -0.305054)
			(stroke
				(width 0.1)
				(type default)
			)
			(layer "F.Fab")
		)
		(fp_line
			(start -0.12065 -0.305054)
			(end -0.12065 -0.2794)
			(stroke
				(width 0.1)
				(type default)
			)
			(layer "F.Fab")
		)
		(fp_line
			(start -0.12065 -0.2794)
			(end 0.12065 -0.2794)
			(stroke
				(width 0.1)
				(type default)
			)
			(layer "F.Fab")
		)
		(fp_line
			(start -0.12065 0.2794)
			(end -0.12065 0.3048)
			(stroke
				(width 0.1)
				(type default)
			)
			(layer "F.Fab")
		)
		(fp_line
			(start -0.12065 0.3048)
			(end -0.67945 0.3048)
			(stroke
				(width 0.1)
				(type default)
			)
			(layer "F.Fab")
		)
		(fp_line
			(start 0.120396 0.2794)
			(end -0.12065 0.2794)
			(stroke
				(width 0.1)
				(type default)
			)
			(layer "F.Fab")
		)
		(fp_line
			(start 0.120396 0.3048)
			(end 0.120396 0.2794)
			(stroke
				(width 0.1)
				(type default)
			)
			(layer "F.Fab")
		)
		(fp_line
			(start 0.12065 -0.3048)
			(end 0.67945 -0.3048)
			(stroke
				(width 0.1)
				(type default)
			)
			(layer "F.Fab")
		)
		(fp_line
			(start 0.12065 -0.2794)
			(end 0.12065 -0.3048)
			(stroke
				(width 0.1)
				(type default)
			)
			(layer "F.Fab")
		)
		(fp_line
			(start 0.67945 -0.3048)
			(end 0.67945 0.3048)
			(stroke
				(width 0.1)
				(type default)
			)
			(layer "F.Fab")
		)
		(fp_line
			(start 0.67945 0.3048)
			(end 0.120396 0.3048)
			(stroke
				(width 0.1)
				(type default)
			)
			(layer "F.Fab")
		)
		(pad "1" smd circle
			(at -0.40005 0)
			(size 0 0)
			(layers "F.Cu" "F.Mask" "F.Paste")
			(net "P3V3_OCP_OV_2")
		)
		(pad "2" smd circle
			(at 0.40005 0)
			(size 0 0)
			(layers "F.Cu" "F.Mask" "F.Paste")
			(net "GND")
		)
	)
)
